(kicad_pcb
	(version 20241229)
	(generator "pcbnew")
	(generator_version "9.0")
	(general
		(thickness 1.62)
		(legacy_teardrops no)
	)
	(paper "A3")
	(title_block
		(title "COM Express 7 Baseboard")
		(date "2025-02-04")
		(rev "1.1.2")
		(company "Antmicro Ltd")
		(comment 1 "www.antmicro.com")
		(comment 9 "footprints 622-626 of 802")
	)
	(layers
		(0 "F.Cu" signal)
		(4 "In1.Cu" signal)
		(6 "In2.Cu" signal)
		(8 "In3.Cu" signal)
		(10 "In4.Cu" signal)
		(12 "In5.Cu" signal)
		(14 "In6.Cu" signal)
		(2 "B.Cu" signal)
		(9 "F.Adhes" user "F.Adhesive")
		(11 "B.Adhes" user "B.Adhesive")
		(13 "F.Paste" user)
		(15 "B.Paste" user)
		(5 "F.SilkS" user "F.Silkscreen")
		(7 "B.SilkS" user "B.Silkscreen")
		(1 "F.Mask" user)
		(3 "B.Mask" user)
		(17 "Dwgs.User" user "User.Drawings")
		(19 "Cmts.User" user "User.Comments")
		(21 "Eco1.User" user "User.Eco1")
		(23 "Eco2.User" user "User.Eco2")
		(25 "Edge.Cuts" user)
		(27 "Margin" user)
		(31 "F.CrtYd" user "F.Courtyard")
		(29 "B.CrtYd" user "B.Courtyard")
		(35 "F.Fab" user)
		(33 "B.Fab" user)
	)
	(footprint "antmicro-footprints:USON-10_2.5x1mm_P0.5mm"
		(layer "B.Cu")
		(at 123.4 104.3)
		(descr "USON-10 2.5x1mm_ Pitch 0.5mm")
		(tags "USON-10 2.5x1mm Pitch 0.5mm")
		(property "Reference" "U2"
			(at -0.85 0.81 90)
			(layer "B.SilkS")
			(effects
				(font
					(size 0.7 0.7)
					(thickness 0.15)
				)
				(justify right bottom mirror)
			)
		)
		(property "Value" "ESD204DQAR"
			(at 0.018 -2.499 0)
			(layer "B.Fab")
			(effects
				(font
					(size 0.7 0.7)
					(thickness 0.15)
				)
				(justify right bottom mirror)
			)
		)
		(property "Datasheet" "https://www.ti.com/lit/ds/symlink/esd204.pdf?ts=1706004844383&ref_url=https%253A%252F%252Fwww.ti.com%252Finterface%252Fdiodes%252Fesd-protection-diodes%252Fproducts.html"
			(at 0 0 0)
			(layer "F.Fab")
			(hide yes)
			(effects
				(font
					(size 1.27 1.27)
					(thickness 0.15)
				)
			)
		)
		(property "Author" "Antmicro"
			(at 0 0 0)
			(layer "B.Fab")
			(hide yes)
			(effects
				(font
					(size 1 1)
					(thickness 0.15)
				)
				(justify mirror)
			)
		)
		(property "License" "Apache-2.0"
			(at 0 0 0)
			(layer "B.Fab")
			(hide yes)
			(effects
				(font
					(size 1 1)
					(thickness 0.15)
				)
				(justify mirror)
			)
		)
		(property "MPN" "ESD204DQAR"
			(at 0 0 0)
			(layer "B.Fab")
			(hide yes)
			(effects
				(font
					(size 1 1)
					(thickness 0.15)
				)
				(justify mirror)
			)
		)
		(property "Manufacturer" "Texas Instruments"
			(at 0 0 0)
			(layer "B.Fab")
			(hide yes)
			(effects
				(font
					(size 1 1)
					(thickness 0.15)
				)
				(justify mirror)
			)
		)
		(sheetname "2xUSB3.0+RJ45")
		(sheetfile "usb3+rj45.kicad_sch")
		(attr smd)
		(fp_line
			(start -0.5 -1.398)
			(end 0.498 -1.398)
			(stroke
				(width 0.15)
				(type solid)
			)
			(layer "B.SilkS")
		)
		(fp_line
			(start -0.5 1.401)
			(end 0.498 1.401)
			(stroke
				(width 0.15)
				(type solid)
			)
			(layer "B.SilkS")
		)
		(fp_circle
			(center -0.68 1.27)
			(end -0.63 1.27)
			(stroke
				(width 0.15)
				(type solid)
			)
			(fill yes)
			(layer "B.SilkS")
		)
		(fp_rect
			(start -0.8 1.5)
			(end 0.8 -1.499)
			(stroke
				(width 0.05)
				(type solid)
			)
			(fill no)
			(layer "B.CrtYd")
		)
		(fp_line
			(start -0.5 -1.249)
			(end -0.5 1)
			(stroke
				(width 0.15)
				(type solid)
			)
			(layer "B.Fab")
		)
		(fp_line
			(start -0.5 1)
			(end -0.25 1.25)
			(stroke
				(width 0.15)
				(type solid)
			)
			(layer "B.Fab")
		)
		(fp_line
			(start -0.25 1.25)
			(end 0.498 1.25)
			(stroke
				(width 0.15)
				(type solid)
			)
			(layer "B.Fab")
		)
		(fp_line
			(start 0.498 -1.249)
			(end -0.5 -1.249)
			(stroke
				(width 0.15)
				(type solid)
			)
			(layer "B.Fab")
		)
		(fp_line
			(start 0.498 -1.249)
			(end 0.498 1.25)
			(stroke
				(width 0.15)
				(type solid)
			)
			(layer "B.Fab")
		)
		(pad "1" smd roundrect
			(at -0.387 1 90)
			(size 0.25 0.55)
			(layers "B.Cu" "B.Mask" "B.Paste")
			(roundrect_rratio 0.25)
			(net 160 "/2xUSB3.0+RJ45/USBSS_2.RX-")
			(pintype "passive")
			(teardrops
				(best_length_ratio 0.2)
				(max_length 1)
				(best_width_ratio 0.9)
				(max_width 2)
				(curved_edges yes)
				(filter_ratio 0.9)
				(enabled yes)
				(allow_two_segments yes)
				(prefer_zone_connections yes)
			)
		)
		(pad "2" smd roundrect
			(at -0.387 0.5 90)
			(size 0.25 0.55)
			(layers "B.Cu" "B.Mask" "B.Paste")
			(roundrect_rratio 0.25)
			(net 161 "/2xUSB3.0+RJ45/USBSS_2.RX+")
			(pintype "passive")
			(teardrops
				(best_length_ratio 0.2)
				(max_length 1)
				(best_width_ratio 0.9)
				(max_width 2)
				(curved_edges yes)
				(filter_ratio 0.9)
				(enabled yes)
				(allow_two_segments yes)
				(prefer_zone_connections yes)
			)
		)
		(pad "3" smd roundrect
			(at -0.387 0 90)
			(size 0.4 0.55)
			(layers "B.Cu" "B.Mask" "B.Paste")
			(roundrect_rratio 0.25)
			(net 1 "GND")
			(pintype "power_in")
			(teardrops
				(best_length_ratio 0.2)
				(max_length 1)
				(best_width_ratio 0.9)
				(max_width 2)
				(curved_edges yes)
				(filter_ratio 0.9)
				(enabled yes)
				(allow_two_segments yes)
				(prefer_zone_connections yes)
			)
		)
		(pad "4" smd roundrect
			(at -0.387 -0.498 90)
			(size 0.25 0.55)
			(layers "B.Cu" "B.Mask" "B.Paste")
			(roundrect_rratio 0.25)
			(net 49 "/2xUSB3.0+RJ45/USBSS_2.TX-")
			(pintype "passive")
			(teardrops
				(best_length_ratio 0.2)
				(max_length 1)
				(best_width_ratio 0.9)
				(max_width 2)
				(curved_edges yes)
				(filter_ratio 0.9)
				(enabled yes)
				(allow_two_segments yes)
				(prefer_zone_connections yes)
			)
		)
		(pad "5" smd roundrect
			(at -0.387 -0.998 90)
			(size 0.25 0.55)
			(layers "B.Cu" "B.Mask" "B.Paste")
			(roundrect_rratio 0.25)
			(net 45 "/2xUSB3.0+RJ45/USBSS_2.TX+")
			(pintype "passive")
			(teardrops
				(best_length_ratio 0.2)
				(max_length 1)
				(best_width_ratio 0.9)
				(max_width 2)
				(curved_edges yes)
				(filter_ratio 0.9)
				(enabled yes)
				(allow_two_segments yes)
				(prefer_zone_connections yes)
			)
		)
		(pad "6" smd roundrect
			(at 0.385 -0.998 90)
			(size 0.25 0.55)
			(layers "B.Cu" "B.Mask" "B.Paste")
			(roundrect_rratio 0.25)
			(net 45 "/2xUSB3.0+RJ45/USBSS_2.TX+")
			(pintype "passive")
			(teardrops
				(best_length_ratio 0.2)
				(max_length 1)
				(best_width_ratio 0.9)
				(max_width 2)
				(curved_edges yes)
				(filter_ratio 0.9)
				(enabled yes)
				(allow_two_segments yes)
				(prefer_zone_connections yes)
			)
		)
		(pad "7" smd roundrect
			(at 0.385 -0.498 90)
			(size 0.25 0.55)
			(layers "B.Cu" "B.Mask" "B.Paste")
			(roundrect_rratio 0.25)
			(net 49 "/2xUSB3.0+RJ45/USBSS_2.TX-")
			(pintype "passive")
			(teardrops
				(best_length_ratio 0.2)
				(max_length 1)
				(best_width_ratio 0.9)
				(max_width 2)
				(curved_edges yes)
				(filter_ratio 0.9)
				(enabled yes)
				(allow_two_segments yes)
				(prefer_zone_connections yes)
			)
		)
		(pad "8" smd roundrect
			(at 0.385 0 90)
			(size 0.4 0.55)
			(layers "B.Cu" "B.Mask" "B.Paste")
			(roundrect_rratio 0.25)
			(net 1 "GND")
			(pintype "passive")
			(teardrops
				(best_length_ratio 0.2)
				(max_length 1)
				(best_width_ratio 0.9)
				(max_width 2)
				(curved_edges yes)
				(filter_ratio 0.9)
				(enabled yes)
				(allow_two_segments yes)
				(prefer_zone_connections yes)
			)
		)
		(pad "9" smd roundrect
			(at 0.385 0.5 90)
			(size 0.25 0.55)
			(layers "B.Cu" "B.Mask" "B.Paste")
			(roundrect_rratio 0.25)
			(net 161 "/2xUSB3.0+RJ45/USBSS_2.RX+")
			(pintype "passive")
			(teardrops
				(best_length_ratio 0.2)
				(max_length 1)
				(best_width_ratio 0.9)
				(max_width 2)
				(curved_edges yes)
				(filter_ratio 0.9)
				(enabled yes)
				(allow_two_segments yes)
				(prefer_zone_connections yes)
			)
		)
		(pad "10" smd roundrect
			(at 0.385 1 90)
			(size 0.25 0.55)
			(layers "B.Cu" "B.Mask" "B.Paste")
			(roundrect_rratio 0.25)
			(net 160 "/2xUSB3.0+RJ45/USBSS_2.RX-")
			(pintype "passive")
			(teardrops
				(best_length_ratio 0.2)
				(max_length 1)
				(best_width_ratio 0.9)
				(max_width 2)
				(curved_edges yes)
				(filter_ratio 0.9)
				(enabled yes)
				(allow_two_segments yes)
				(prefer_zone_connections yes)
			)
		)
	)
	(footprint "antmicro-footprints:C_0402_1005Metric"
		(layer "B.Cu")
		(at 148.45 142.36 90)
		(descr "Capacitor SMD 0402")
		(tags "capacitor SMD 0402")
		(property "Reference" "C162"
			(at -1.35 -0.5 90)
			(layer "B.SilkS")
			(effects
				(font
					(size 0.7 0.7)
					(thickness 0.15)
				)
				(justify right bottom mirror)
			)
		)
		(property "Value" "C_100n_0402"
			(at -1.022927 -2.155213 90)
			(layer "B.Fab")
			(effects
				(font
					(size 0.7 0.7)
					(thickness 0.15)
				)
				(justify right bottom mirror)
			)
		)
		(property "Datasheet" "https://www.murata.com/products/productdetail?partno=GRM155R61H104KE14%23"
			(at 0 0 90)
			(layer "F.Fab")
			(hide yes)
			(effects
				(font
					(size 1.27 1.27)
					(thickness 0.15)
				)
			)
		)
		(property "Author" "Antmicro"
			(at 290.81 -6.09 0)
			(layer "B.Fab")
			(hide yes)
			(effects
				(font
					(size 1 1)
					(thickness 0.15)
				)
				(justify mirror)
			)
		)
		(property "Dielectric" "X5R"
			(at 290.81 -6.09 0)
			(layer "B.Fab")
			(hide yes)
			(effects
				(font
					(size 1 1)
					(thickness 0.15)
				)
				(justify mirror)
			)
		)
		(property "License" "Apache-2.0"
			(at 290.81 -6.09 0)
			(layer "B.Fab")
			(hide yes)
			(effects
				(font
					(size 1 1)
					(thickness 0.15)
				)
				(justify mirror)
			)
		)
		(property "MPN" "GRM155R61H104KE14D"
			(at 290.81 -6.09 0)
			(layer "B.Fab")
			(hide yes)
			(effects
				(font
					(size 1 1)
					(thickness 0.15)
				)
				(justify mirror)
			)
		)
		(property "Manufacturer" "Murata"
			(at 290.81 -6.09 0)
			(layer "B.Fab")
			(hide yes)
			(effects
				(font
					(size 1 1)
					(thickness 0.15)
				)
				(justify mirror)
			)
		)
		(property "Public" "False"
			(at 290.81 -6.09 0)
			(layer "B.Fab")
			(hide yes)
			(effects
				(font
					(size 1 1)
					(thickness 0.15)
				)
				(justify mirror)
			)
		)
		(property "Val" "100n"
			(at 290.81 -6.09 0)
			(layer "B.Fab")
			(hide yes)
			(effects
				(font
					(size 1 1)
					(thickness 0.15)
				)
				(justify mirror)
			)
		)
		(property "Voltage" "50V"
			(at 290.81 -6.09 0)
			(layer "B.Fab")
			(hide yes)
			(effects
				(font
					(size 1 1)
					(thickness 0.15)
				)
				(justify mirror)
			)
		)
		(sheetname "KR to SFI #1")
		(sheetfile "kr_sfi.kicad_sch")
		(attr smd)
		(fp_rect
			(start -0.925 0.47)
			(end 0.925 -0.47)
			(stroke
				(width 0.05)
				(type default)
			)
			(fill no)
			(layer "B.CrtYd")
		)
		(fp_line
			(start 0.504 -0.248)
			(end 0.504 0.25)
			(stroke
				(width 0.15)
				(type solid)
			)
			(layer "B.Fab")
		)
		(fp_line
			(start -0.494 -0.248)
			(end 0.504 -0.248)
			(stroke
				(width 0.15)
				(type solid)
			)
			(layer "B.Fab")
		)
		(fp_line
			(start 0.504 0.25)
			(end -0.494 0.25)
			(stroke
				(width 0.15)
				(type solid)
			)
			(layer "B.Fab")
		)
		(fp_line
			(start -0.494 0.25)
			(end -0.494 -0.248)
			(stroke
				(width 0.15)
				(type solid)
			)
			(layer "B.Fab")
		)
		(pad "1" smd roundrect
			(at -0.48 0 90)
			(size 0.59 0.64)
			(layers "B.Cu" "B.Mask" "B.Paste")
			(roundrect_rratio 0.25)
			(net 1 "GND")
			(pintype "passive")
			(teardrops
				(best_length_ratio 0.2)
				(max_length 1)
				(best_width_ratio 0.9)
				(max_width 2)
				(curved_edges yes)
				(filter_ratio 0.9)
				(enabled yes)
				(allow_two_segments yes)
				(prefer_zone_connections yes)
			)
		)
		(pad "2" smd roundrect
			(at 0.48 0 90)
			(size 0.59 0.64)
			(layers "B.Cu" "B.Mask" "B.Paste")
			(roundrect_rratio 0.25)
			(net 78 "+1V8")
			(pintype "passive")
			(teardrops
				(best_length_ratio 0.2)
				(max_length 1)
				(best_width_ratio 0.9)
				(max_width 2)
				(curved_edges yes)
				(filter_ratio 0.9)
				(enabled yes)
				(allow_two_segments yes)
				(prefer_zone_connections yes)
			)
		)
	)
	(footprint "antmicro-footprints:C_0402_1005Metric"
		(layer "B.Cu")
		(at 133.29 136.36 -90)
		(descr "Capacitor SMD 0402")
		(tags "capacitor SMD 0402")
		(property "Reference" "C201"
			(at -1.2 -1.36 90)
			(layer "B.SilkS")
			(effects
				(font
					(size 0.7 0.7)
					(thickness 0.15)
				)
				(justify left bottom mirror)
			)
		)
		(property "Value" "C_100n_0402"
			(at -1.022927 -2.155213 90)
			(layer "B.Fab")
			(effects
				(font
					(size 0.7 0.7)
					(thickness 0.15)
				)
				(justify left bottom mirror)
			)
		)
		(property "Datasheet" "https://www.murata.com/products/productdetail?partno=GRM155R61H104KE14%23"
			(at 0 0 270)
			(layer "F.Fab")
			(hide yes)
			(effects
				(font
					(size 1.27 1.27)
					(thickness 0.15)
				)
			)
		)
		(property "Author" "Antmicro"
			(at -3.07 269.65 0)
			(layer "B.Fab")
			(hide yes)
			(effects
				(font
					(size 1 1)
					(thickness 0.15)
				)
				(justify mirror)
			)
		)
		(property "Dielectric" "X5R"
			(at -3.07 269.65 0)
			(layer "B.Fab")
			(hide yes)
			(effects
				(font
					(size 1 1)
					(thickness 0.15)
				)
				(justify mirror)
			)
		)
		(property "License" "Apache-2.0"
			(at -3.07 269.65 0)
			(layer "B.Fab")
			(hide yes)
			(effects
				(font
					(size 1 1)
					(thickness 0.15)
				)
				(justify mirror)
			)
		)
		(property "MPN" "GRM155R61H104KE14D"
			(at -3.07 269.65 0)
			(layer "B.Fab")
			(hide yes)
			(effects
				(font
					(size 1 1)
					(thickness 0.15)
				)
				(justify mirror)
			)
		)
		(property "Manufacturer" "Murata"
			(at -3.07 269.65 0)
			(layer "B.Fab")
			(hide yes)
			(effects
				(font
					(size 1 1)
					(thickness 0.15)
				)
				(justify mirror)
			)
		)
		(property "Public" "False"
			(at -3.07 269.65 0)
			(layer "B.Fab")
			(hide yes)
			(effects
				(font
					(size 1 1)
					(thickness 0.15)
				)
				(justify mirror)
			)
		)
		(property "Val" "100n"
			(at -3.07 269.65 0)
			(layer "B.Fab")
			(hide yes)
			(effects
				(font
					(size 1 1)
					(thickness 0.15)
				)
				(justify mirror)
			)
		)
		(property "Voltage" "50V"
			(at -3.07 269.65 0)
			(layer "B.Fab")
			(hide yes)
			(effects
				(font
					(size 1 1)
					(thickness 0.15)
				)
				(justify mirror)
			)
		)
		(sheetname "KR to SFI #2")
		(sheetfile "kr_sfi.kicad_sch")
		(attr smd)
		(fp_rect
			(start -0.925 0.47)
			(end 0.925 -0.47)
			(stroke
				(width 0.05)
				(type default)
			)
			(fill no)
			(layer "B.CrtYd")
		)
		(fp_line
			(start -0.494 0.25)
			(end -0.494 -0.248)
			(stroke
				(width 0.15)
				(type solid)
			)
			(layer "B.Fab")
		)
		(fp_line
			(start 0.504 0.25)
			(end -0.494 0.25)
			(stroke
				(width 0.15)
				(type solid)
			)
			(layer "B.Fab")
		)
		(fp_line
			(start -0.494 -0.248)
			(end 0.504 -0.248)
			(stroke
				(width 0.15)
				(type solid)
			)
			(layer "B.Fab")
		)
		(fp_line
			(start 0.504 -0.248)
			(end 0.504 0.25)
			(stroke
				(width 0.15)
				(type solid)
			)
			(layer "B.Fab")
		)
		(pad "1" smd roundrect
			(at -0.48 0 270)
			(size 0.59 0.64)
			(layers "B.Cu" "B.Mask" "B.Paste")
			(roundrect_rratio 0.25)
			(net 1 "GND")
			(pintype "passive")
			(teardrops
				(best_length_ratio 0.2)
				(max_length 1)
				(best_width_ratio 0.9)
				(max_width 2)
				(curved_edges yes)
				(filter_ratio 0.9)
				(enabled yes)
				(allow_two_segments yes)
				(prefer_zone_connections yes)
			)
		)
		(pad "2" smd roundrect
			(at 0.48 0 270)
			(size 0.59 0.64)
			(layers "B.Cu" "B.Mask" "B.Paste")
			(roundrect_rratio 0.25)
			(net 74 "+1V0")
			(pintype "passive")
			(teardrops
				(best_length_ratio 0.2)
				(max_length 1)
				(best_width_ratio 0.9)
				(max_width 2)
				(curved_edges yes)
				(filter_ratio 0.9)
				(enabled yes)
				(allow_two_segments yes)
				(prefer_zone_connections yes)
			)
		)
	)
	(footprint "antmicro-footprints:TP_SMD_0.75mm"
		(layer "B.Cu")
		(at 157.7 162.46 -90)
		(property "Reference" "TP1"
			(at -2.437 -0.449 90)
			(layer "B.SilkS")
			(effects
				(font
					(size 0.7 0.7)
					(thickness 0.15)
				)
				(justify left bottom mirror)
			)
		)
		(property "Value" "TP_0.75mm_SMD"
			(at 0 -1.2 90)
			(layer "B.Fab")
			(effects
				(font
					(size 0.7 0.7)
					(thickness 0.15)
				)
				(justify left bottom mirror)
			)
		)
		(property "Author" "Antmicro"
			(at -4.76 320.16 0)
			(layer "B.Fab")
			(hide yes)
			(effects
				(font
					(size 1 1)
					(thickness 0.15)
				)
				(justify mirror)
			)
		)
		(property "License" "Apache-2.0"
			(at -4.76 320.16 0)
			(layer "B.Fab")
			(hide yes)
			(effects
				(font
					(size 1 1)
					(thickness 0.15)
				)
				(justify mirror)
			)
		)
		(property "MPN" ""
			(at -4.76 320.16 0)
			(layer "B.Fab")
			(hide yes)
			(effects
				(font
					(size 1 1)
					(thickness 0.15)
				)
				(justify mirror)
			)
		)
		(property "Manufacturer" ""
			(at -4.76 320.16 0)
			(layer "B.Fab")
			(hide yes)
			(effects
				(font
					(size 1 1)
					(thickness 0.15)
				)
				(justify mirror)
			)
		)
		(property "Public" "False"
			(at -4.76 320.16 0)
			(layer "B.Fab")
			(hide yes)
			(effects
				(font
					(size 1 1)
					(thickness 0.15)
				)
				(justify mirror)
			)
		)
		(sheetname "2xSFP+")
		(sheetfile "2xSFP+.kicad_sch")
		(attr exclude_from_pos_files exclude_from_bom)
		(fp_circle
			(center 0 0)
			(end 0.475 0)
			(stroke
				(width 0.05)
				(type default)
			)
			(fill no)
			(layer "B.CrtYd")
		)
		(pad "1" smd circle
			(at 0 0 270)
			(size 0.75 0.75)
			(layers "B.Cu" "B.Mask")
			(net 697 "Net-(U5-IO0_6)")
			(pinfunction "1")
			(pintype "passive")
			(teardrops
				(best_length_ratio 0.4)
				(max_length 1)
				(best_width_ratio 0.9)
				(max_width 2)
				(curved_edges yes)
				(filter_ratio 0.9)
				(enabled yes)
				(allow_two_segments yes)
				(prefer_zone_connections yes)
			)
		)
	)
	(footprint "antmicro-footprints:TP_SMD_0.75mm"
		(layer "B.Cu")
		(at 176.25 165.05)
		(property "Reference" "TP23"
			(at 1 -0.3 180)
			(layer "B.SilkS")
			(effects
				(font
					(size 0.7 0.7)
					(thickness 0.15)
				)
				(justify right top mirror)
			)
		)
		(property "Value" "TP_0.75mm_SMD"
			(at 3.225 -53.865 0)
			(layer "B.Fab")
			(hide yes)
			(effects
				(font
					(size 0.7 0.7)
					(thickness 0.15)
				)
				(justify right top mirror)
			)
		)
		(property "Author" "Antmicro"
			(at 456 306.12 0)
			(layer "B.Fab")
			(hide yes)
			(effects
				(font
					(size 1 1)
					(thickness 0.15)
				)
				(justify mirror)
			)
		)
		(property "License" "Apache-2.0"
			(at 456 306.12 0)
			(layer "B.Fab")
			(hide yes)
			(effects
				(font
					(size 1 1)
					(thickness 0.15)
				)
				(justify mirror)
			)
		)
		(property "MPN" ""
			(at 456 306.12 0)
			(layer "B.Fab")
			(hide yes)
			(effects
				(font
					(size 1 1)
					(thickness 0.15)
				)
				(justify mirror)
			)
		)
		(property "Manufacturer" ""
			(at 456 306.12 0)
			(layer "B.Fab")
			(hide yes)
			(effects
				(font
					(size 1 1)
					(thickness 0.15)
				)
				(justify mirror)
			)
		)
		(property "Public" "False"
			(at 456 306.12 0)
			(layer "B.Fab")
			(hide yes)
			(effects
				(font
					(size 1 1)
					(thickness 0.15)
				)
				(justify mirror)
			)
		)
		(sheetname "Com Express 7 MGMT")
		(sheetfile "com_express_7_mgmt.kicad_sch")
		(attr exclude_from_pos_files exclude_from_bom)
		(fp_circle
			(center 0 0)
			(end 0.475 0)
			(stroke
				(width 0.05)
				(type default)
			)
			(fill no)
			(layer "B.CrtYd")
		)
		(pad "1" smd circle
			(at 0 0)
			(size 0.75 0.75)
			(layers "B.Cu" "B.Mask")
			(net 351 "Net-(J12D-LPC_AD2{slash}ESPI_IO_2)")
			(pinfunction "1")
			(pintype "passive")
			(teardrops
				(best_length_ratio 0.4)
				(max_length 1)
				(best_width_ratio 0.9)
				(max_width 2)
				(curved_edges yes)
				(filter_ratio 0.9)
				(enabled yes)
				(allow_two_segments yes)
				(prefer_zone_connections yes)
			)
		)
	)
)
